(kicad_pcb
	(version 20260206)
	(generator "pcbnew")
	(generator_version "10.0")
	(general
		(thickness 1.6)
		(legacy_teardrops no)
	)
	(paper "A4")
	(title_block
		(title "03242023_DA0F0TMBIJ0_F0T_Motherboard_J_brd_V01_OCP.brd")
		(comment 1 "Grand Teton / footprints 4446-4452 of 6105")
	)
	(layers
		(0 "F.Cu" signal "TOP")
		(4 "In1.Cu" signal "GND")
		(6 "In2.Cu" signal "IN1")
		(8 "In3.Cu" signal "GND1")
		(10 "In4.Cu" signal "IN2")
		(12 "In5.Cu" signal "GND2")
		(14 "In6.Cu" signal "IN3")
		(16 "In7.Cu" signal "GND3")
		(18 "In8.Cu" signal "VCC")
		(20 "In9.Cu" signal "VCC1")
		(22 "In10.Cu" signal "GND4")
		(24 "In11.Cu" signal "IN4")
		(26 "In12.Cu" signal "GND5")
		(28 "In13.Cu" signal "IN5")
		(30 "In14.Cu" signal "GND6")
		(32 "In15.Cu" signal "IN6")
		(34 "In16.Cu" signal "GND7")
		(2 "B.Cu" signal "BOTTOM")
		(9 "F.Adhes" user "F.Adhesive")
		(11 "B.Adhes" user "B.Adhesive")
		(13 "F.Paste" user "Package Geometry/Pastemask Top")
		(15 "B.Paste" user "Package Geometry/Pastemask Bottom")
		(5 "F.SilkS" user "Ref Des/Silkscreen Top")
		(7 "B.SilkS" user "Ref Des/Silkscreen Bottom")
		(1 "F.Mask" user "Board Geometry/Soldermask Top")
		(3 "B.Mask" user "Board Geometry/Soldermask Bottom")
		(17 "Dwgs.User" user "User.Drawings")
		(19 "Cmts.User" user "User.Comments")
		(21 "Eco1.User" user "User.Eco1")
		(23 "Eco2.User" user "User.Eco2")
		(25 "Edge.Cuts" user "Board Geometry/Outline")
		(27 "Margin" user)
		(31 "F.CrtYd" user "Package Geometry/Place Bound Top")
		(29 "B.CrtYd" user "Package Geometry/Place Bound Bottom")
		(35 "F.Fab" user "Ref Des/Assembly Top")
		(33 "B.Fab" user "Ref Des/Assembly Bottom")
	)
	(footprint ""
		(layer "B.Cu")
		(at 322.984622 -57.267348 180)
		(property "Reference" "R1200"
			(at 0 0 0)
			(layer "B.SilkS")
			(hide yes)
			(effects
				(font
					(size 1.27 1.27)
				)
				(justify mirror)
			)
		)
		(property "Value" ""
			(at 0 0 0)
			(layer "B.Fab")
			(effects
				(font
					(size 1.27 1.27)
				)
				(justify mirror)
			)
		)
		(duplicate_pad_numbers_are_jumpers no)
		(fp_line
			(start 0.7874 0.4064)
			(end 0.7874 -0.4064)
			(stroke
				(width 0.1524)
				(type default)
			)
			(layer "B.SilkS")
		)
		(fp_line
			(start 0.7874 -0.4064)
			(end -0.7874 -0.4064)
			(stroke
				(width 0.1524)
				(type default)
			)
			(layer "B.SilkS")
		)
		(fp_line
			(start -0.7874 0.4064)
			(end 0.7874 0.4064)
			(stroke
				(width 0.1524)
				(type default)
			)
			(layer "B.SilkS")
		)
		(fp_line
			(start -0.7874 -0.4064)
			(end -0.7874 0.4064)
			(stroke
				(width 0.1524)
				(type default)
			)
			(layer "B.SilkS")
		)
		(fp_line
			(start 0.67945 0.3048)
			(end 0.67945 -0.305054)
			(stroke
				(width 0.1)
				(type default)
			)
			(layer "B.Fab")
		)
		(fp_line
			(start 0.67945 -0.305054)
			(end 0.12065 -0.305054)
			(stroke
				(width 0.1)
				(type default)
			)
			(layer "B.Fab")
		)
		(fp_line
			(start 0.12065 0.3048)
			(end 0.67945 0.3048)
			(stroke
				(width 0.1)
				(type default)
			)
			(layer "B.Fab")
		)
		(fp_line
			(start 0.12065 0.2794)
			(end 0.12065 0.3048)
			(stroke
				(width 0.1)
				(type default)
			)
			(layer "B.Fab")
		)
		(fp_line
			(start 0.12065 -0.2794)
			(end -0.12065 -0.2794)
			(stroke
				(width 0.1)
				(type default)
			)
			(layer "B.Fab")
		)
		(fp_line
			(start 0.12065 -0.305054)
			(end 0.12065 -0.2794)
			(stroke
				(width 0.1)
				(type default)
			)
			(layer "B.Fab")
		)
		(fp_line
			(start -0.120396 0.3048)
			(end -0.120396 0.2794)
			(stroke
				(width 0.1)
				(type default)
			)
			(layer "B.Fab")
		)
		(fp_line
			(start -0.120396 0.2794)
			(end 0.12065 0.2794)
			(stroke
				(width 0.1)
				(type default)
			)
			(layer "B.Fab")
		)
		(fp_line
			(start -0.12065 -0.2794)
			(end -0.12065 -0.3048)
			(stroke
				(width 0.1)
				(type default)
			)
			(layer "B.Fab")
		)
		(fp_line
			(start -0.12065 -0.3048)
			(end -0.67945 -0.3048)
			(stroke
				(width 0.1)
				(type default)
			)
			(layer "B.Fab")
		)
		(fp_line
			(start -0.67945 0.3048)
			(end -0.120396 0.3048)
			(stroke
				(width 0.1)
				(type default)
			)
			(layer "B.Fab")
		)
		(fp_line
			(start -0.67945 -0.3048)
			(end -0.67945 0.3048)
			(stroke
				(width 0.1)
				(type default)
			)
			(layer "B.Fab")
		)
		(pad "1" smd circle
			(at 0.40005 0)
			(size 0 0)
			(layers "B.Cu" "B.Mask" "B.Paste")
			(net "FM_PCH_TRIGGER0_N")
		)
		(pad "2" smd circle
			(at -0.40005 0)
			(size 0 0)
			(layers "B.Cu" "B.Mask" "B.Paste")
			(net "FM_PCH_TRIGGER0_R_N")
		)
	)
	(footprint ""
		(layer "B.Cu")
		(at 49.936146 -321.554856 -90)
		(property "Reference" "C60"
			(at 0 0 90)
			(layer "B.SilkS")
			(hide yes)
			(effects
				(font
					(size 1.27 1.27)
				)
				(justify mirror)
			)
		)
		(property "Value" ""
			(at 0 0 90)
			(layer "B.Fab")
			(effects
				(font
					(size 1.27 1.27)
				)
				(justify mirror)
			)
		)
		(duplicate_pad_numbers_are_jumpers no)
		(fp_line
			(start -1.524 0.762)
			(end 1.524 0.762)
			(stroke
				(width 0.1524)
				(type default)
			)
			(layer "B.SilkS")
		)
		(fp_line
			(start 1.524 0.762)
			(end 1.524 -0.762)
			(stroke
				(width 0.1524)
				(type default)
			)
			(layer "B.SilkS")
		)
		(fp_line
			(start -1.524 -0.762)
			(end -1.524 0.762)
			(stroke
				(width 0.1524)
				(type default)
			)
			(layer "B.SilkS")
		)
		(fp_line
			(start 1.524 -0.762)
			(end -1.524 -0.762)
			(stroke
				(width 0.1524)
				(type default)
			)
			(layer "B.SilkS")
		)
		(fp_line
			(start -1.1049 0.724916)
			(end -1.1049 -0.724916)
			(stroke
				(width 0.1)
				(type default)
			)
			(layer "B.Fab")
		)
		(fp_line
			(start 1.1049 0.724916)
			(end -1.1049 0.724916)
			(stroke
				(width 0.1)
				(type default)
			)
			(layer "B.Fab")
		)
		(fp_line
			(start -1.1049 -0.724916)
			(end 1.1049 -0.724916)
			(stroke
				(width 0.1)
				(type default)
			)
			(layer "B.Fab")
		)
		(fp_line
			(start 1.1049 -0.724916)
			(end 1.1049 0.724916)
			(stroke
				(width 0.1)
				(type default)
			)
			(layer "B.Fab")
		)
		(pad "1" smd rect
			(at 0.889 0 270)
			(size 1.016 1.27)
			(layers "B.Cu" "B.Mask" "B.Paste")
			(net "P12V_S3_AUX_CPU1_NVDIMM")
		)
		(pad "2" smd rect
			(at -0.889 0 270)
			(size 1.016 1.27)
			(layers "B.Cu" "B.Mask" "B.Paste")
			(net "GND")
		)
	)
	(footprint ""
		(layer "B.Cu")
		(at 295.93413 -403.031452 90)
		(property "Reference" "PR2512"
			(at 0 0 90)
			(layer "B.SilkS")
			(hide yes)
			(effects
				(font
					(size 1.27 1.27)
				)
				(justify mirror)
			)
		)
		(property "Value" ""
			(at 0 0 90)
			(layer "B.Fab")
			(effects
				(font
					(size 1.27 1.27)
				)
				(justify mirror)
			)
		)
		(duplicate_pad_numbers_are_jumpers no)
		(fp_line
			(start 0.7874 -0.4064)
			(end -0.7874 -0.4064)
			(stroke
				(width 0.1524)
				(type default)
			)
			(layer "B.SilkS")
		)
		(fp_line
			(start -0.7874 -0.4064)
			(end -0.7874 0.4064)
			(stroke
				(width 0.1524)
				(type default)
			)
			(layer "B.SilkS")
		)
		(fp_line
			(start 0.7874 0.4064)
			(end 0.7874 -0.4064)
			(stroke
				(width 0.1524)
				(type default)
			)
			(layer "B.SilkS")
		)
		(fp_line
			(start -0.7874 0.4064)
			(end 0.7874 0.4064)
			(stroke
				(width 0.1524)
				(type default)
			)
			(layer "B.SilkS")
		)
		(fp_line
			(start 0.67945 -0.305054)
			(end 0.12065 -0.305054)
			(stroke
				(width 0.1)
				(type default)
			)
			(layer "B.Fab")
		)
		(fp_line
			(start 0.12065 -0.305054)
			(end 0.12065 -0.2794)
			(stroke
				(width 0.1)
				(type default)
			)
			(layer "B.Fab")
		)
		(fp_line
			(start -0.12065 -0.3048)
			(end -0.67945 -0.3048)
			(stroke
				(width 0.1)
				(type default)
			)
			(layer "B.Fab")
		)
		(fp_line
			(start -0.67945 -0.3048)
			(end -0.67945 0.3048)
			(stroke
				(width 0.1)
				(type default)
			)
			(layer "B.Fab")
		)
		(fp_line
			(start 0.12065 -0.2794)
			(end -0.12065 -0.2794)
			(stroke
				(width 0.1)
				(type default)
			)
			(layer "B.Fab")
		)
		(fp_line
			(start -0.12065 -0.2794)
			(end -0.12065 -0.3048)
			(stroke
				(width 0.1)
				(type default)
			)
			(layer "B.Fab")
		)
		(fp_line
			(start 0.12065 0.2794)
			(end 0.12065 0.3048)
			(stroke
				(width 0.1)
				(type default)
			)
			(layer "B.Fab")
		)
		(fp_line
			(start -0.120396 0.2794)
			(end 0.12065 0.2794)
			(stroke
				(width 0.1)
				(type default)
			)
			(layer "B.Fab")
		)
		(fp_line
			(start 0.67945 0.3048)
			(end 0.67945 -0.305054)
			(stroke
				(width 0.1)
				(type default)
			)
			(layer "B.Fab")
		)
		(fp_line
			(start 0.12065 0.3048)
			(end 0.67945 0.3048)
			(stroke
				(width 0.1)
				(type default)
			)
			(layer "B.Fab")
		)
		(fp_line
			(start -0.120396 0.3048)
			(end -0.120396 0.2794)
			(stroke
				(width 0.1)
				(type default)
			)
			(layer "B.Fab")
		)
		(fp_line
			(start -0.67945 0.3048)
			(end -0.120396 0.3048)
			(stroke
				(width 0.1)
				(type default)
			)
			(layer "B.Fab")
		)
		(pad "1" smd circle
			(at 0.40005 0 270)
			(size 0 0)
			(layers "B.Cu" "B.Mask" "B.Paste")
			(net "P12V_HSC_ADC_P")
		)
		(pad "2" smd circle
			(at -0.40005 0 270)
			(size 0 0)
			(layers "B.Cu" "B.Mask" "B.Paste")
			(net "P12V_HSC_SENSE2_R3_P")
		)
	)
	(footprint ""
		(layer "B.Cu")
		(at 417.282122 -362.107226 90)
		(property "Reference" "PC610_P0_1"
			(at 0 0 90)
			(layer "B.SilkS")
			(hide yes)
			(effects
				(font
					(size 1.27 1.27)
				)
				(justify mirror)
			)
		)
		(property "Value" ""
			(at 0 0 90)
			(layer "B.Fab")
			(effects
				(font
					(size 1.27 1.27)
				)
				(justify mirror)
			)
		)
		(duplicate_pad_numbers_are_jumpers no)
		(fp_line
			(start 1.524 -0.762)
			(end -1.524 -0.762)
			(stroke
				(width 0.1524)
				(type default)
			)
			(layer "B.SilkS")
		)
		(fp_line
			(start -1.524 -0.762)
			(end -1.524 0.762)
			(stroke
				(width 0.1524)
				(type default)
			)
			(layer "B.SilkS")
		)
		(fp_line
			(start 1.524 0.762)
			(end 1.524 -0.762)
			(stroke
				(width 0.1524)
				(type default)
			)
			(layer "B.SilkS")
		)
		(fp_line
			(start -1.524 0.762)
			(end 1.524 0.762)
			(stroke
				(width 0.1524)
				(type default)
			)
			(layer "B.SilkS")
		)
		(fp_line
			(start 1.1049 -0.724916)
			(end 1.1049 0.724916)
			(stroke
				(width 0.1)
				(type default)
			)
			(layer "B.Fab")
		)
		(fp_line
			(start -1.1049 -0.724916)
			(end 1.1049 -0.724916)
			(stroke
				(width 0.1)
				(type default)
			)
			(layer "B.Fab")
		)
		(fp_line
			(start 1.1049 0.724916)
			(end -1.1049 0.724916)
			(stroke
				(width 0.1)
				(type default)
			)
			(layer "B.Fab")
		)
		(fp_line
			(start -1.1049 0.724916)
			(end -1.1049 -0.724916)
			(stroke
				(width 0.1)
				(type default)
			)
			(layer "B.Fab")
		)
		(pad "1" smd rect
			(at 0.889 0 90)
			(size 1.016 1.27)
			(layers "B.Cu" "B.Mask" "B.Paste")
			(net "SW_P12V_PVCCFA_EHV_FIVRA_CPU0_R")
		)
		(pad "2" smd rect
			(at -0.889 0 90)
			(size 1.016 1.27)
			(layers "B.Cu" "B.Mask" "B.Paste")
			(net "GND")
		)
	)
	(footprint ""
		(layer "B.Cu")
		(at 103.901494 -259.533136 -90)
		(property "Reference" "C448"
			(at 0 0 90)
			(layer "B.SilkS")
			(hide yes)
			(effects
				(font
					(size 1.27 1.27)
				)
				(justify mirror)
			)
		)
		(property "Value" ""
			(at 0 0 90)
			(layer "B.Fab")
			(effects
				(font
					(size 1.27 1.27)
				)
				(justify mirror)
			)
		)
		(duplicate_pad_numbers_are_jumpers no)
		(fp_line
			(start -1.524 0.762)
			(end 1.524 0.762)
			(stroke
				(width 0.1524)
				(type default)
			)
			(layer "B.SilkS")
		)
		(fp_line
			(start 1.524 0.762)
			(end 1.524 -0.762)
			(stroke
				(width 0.1524)
				(type default)
			)
			(layer "B.SilkS")
		)
		(fp_line
			(start -1.524 -0.762)
			(end -1.524 0.762)
			(stroke
				(width 0.1524)
				(type default)
			)
			(layer "B.SilkS")
		)
		(fp_line
			(start 1.524 -0.762)
			(end -1.524 -0.762)
			(stroke
				(width 0.1524)
				(type default)
			)
			(layer "B.SilkS")
		)
		(fp_line
			(start -1.1049 0.724916)
			(end -1.1049 -0.724916)
			(stroke
				(width 0.1)
				(type default)
			)
			(layer "B.Fab")
		)
		(fp_line
			(start 1.1049 0.724916)
			(end -1.1049 0.724916)
			(stroke
				(width 0.1)
				(type default)
			)
			(layer "B.Fab")
		)
		(fp_line
			(start -1.1049 -0.724916)
			(end 1.1049 -0.724916)
			(stroke
				(width 0.1)
				(type default)
			)
			(layer "B.Fab")
		)
		(fp_line
			(start 1.1049 -0.724916)
			(end 1.1049 0.724916)
			(stroke
				(width 0.1)
				(type default)
			)
			(layer "B.Fab")
		)
		(pad "1" smd rect
			(at 0.889 0 270)
			(size 1.016 1.27)
			(layers "B.Cu" "B.Mask" "B.Paste")
			(net "PVCCFA_EHV_CPU1")
		)
		(pad "2" smd rect
			(at -0.889 0 270)
			(size 1.016 1.27)
			(layers "B.Cu" "B.Mask" "B.Paste")
			(net "GND")
		)
	)
	(footprint ""
		(layer "B.Cu")
		(at 341.511128 -336.278474 -90)
		(property "Reference" "PR155"
			(at 0 0 90)
			(layer "B.SilkS")
			(hide yes)
			(effects
				(font
					(size 1.27 1.27)
				)
				(justify mirror)
			)
		)
		(property "Value" ""
			(at 0 0 90)
			(layer "B.Fab")
			(effects
				(font
					(size 1.27 1.27)
				)
				(justify mirror)
			)
		)
		(duplicate_pad_numbers_are_jumpers no)
		(fp_line
			(start -0.7874 0.4064)
			(end 0.7874 0.4064)
			(stroke
				(width 0.1524)
				(type default)
			)
			(layer "B.SilkS")
		)
		(fp_line
			(start 0.7874 0.4064)
			(end 0.7874 -0.4064)
			(stroke
				(width 0.1524)
				(type default)
			)
			(layer "B.SilkS")
		)
		(fp_line
			(start -0.7874 -0.4064)
			(end -0.7874 0.4064)
			(stroke
				(width 0.1524)
				(type default)
			)
			(layer "B.SilkS")
		)
		(fp_line
			(start 0.7874 -0.4064)
			(end -0.7874 -0.4064)
			(stroke
				(width 0.1524)
				(type default)
			)
			(layer "B.SilkS")
		)
		(fp_line
			(start -0.67945 0.3048)
			(end -0.120396 0.3048)
			(stroke
				(width 0.1)
				(type default)
			)
			(layer "B.Fab")
		)
		(fp_line
			(start -0.120396 0.3048)
			(end -0.120396 0.2794)
			(stroke
				(width 0.1)
				(type default)
			)
			(layer "B.Fab")
		)
		(fp_line
			(start 0.12065 0.3048)
			(end 0.67945 0.3048)
			(stroke
				(width 0.1)
				(type default)
			)
			(layer "B.Fab")
		)
		(fp_line
			(start 0.67945 0.3048)
			(end 0.67945 -0.305054)
			(stroke
				(width 0.1)
				(type default)
			)
			(layer "B.Fab")
		)
		(fp_line
			(start -0.120396 0.2794)
			(end 0.12065 0.2794)
			(stroke
				(width 0.1)
				(type default)
			)
			(layer "B.Fab")
		)
		(fp_line
			(start 0.12065 0.2794)
			(end 0.12065 0.3048)
			(stroke
				(width 0.1)
				(type default)
			)
			(layer "B.Fab")
		)
		(fp_line
			(start -0.12065 -0.2794)
			(end -0.12065 -0.3048)
			(stroke
				(width 0.1)
				(type default)
			)
			(layer "B.Fab")
		)
		(fp_line
			(start 0.12065 -0.2794)
			(end -0.12065 -0.2794)
			(stroke
				(width 0.1)
				(type default)
			)
			(layer "B.Fab")
		)
		(fp_line
			(start -0.67945 -0.3048)
			(end -0.67945 0.3048)
			(stroke
				(width 0.1)
				(type default)
			)
			(layer "B.Fab")
		)
		(fp_line
			(start -0.12065 -0.3048)
			(end -0.67945 -0.3048)
			(stroke
				(width 0.1)
				(type default)
			)
			(layer "B.Fab")
		)
		(fp_line
			(start 0.12065 -0.305054)
			(end 0.12065 -0.2794)
			(stroke
				(width 0.1)
				(type default)
			)
			(layer "B.Fab")
		)
		(fp_line
			(start 0.67945 -0.305054)
			(end 0.12065 -0.305054)
			(stroke
				(width 0.1)
				(type default)
			)
			(layer "B.Fab")
		)
		(pad "1" smd circle
			(at 0.40005 0 90)
			(size 0 0)
			(layers "B.Cu" "B.Mask" "B.Paste")
			(net "PVCCIN_CPU0_VOS1")
		)
		(pad "2" smd circle
			(at -0.40005 0 90)
			(size 0 0)
			(layers "B.Cu" "B.Mask" "B.Paste")
			(net "PVCCIN_CPU0")
		)
	)
	(footprint ""
		(layer "B.Cu")
		(at 257.35407 -55.436262)
		(property "Reference" "R3942"
			(at 0 0 0)
			(layer "B.SilkS")
			(hide yes)
			(effects
				(font
					(size 1.27 1.27)
				)
				(justify mirror)
			)
		)
		(property "Value" ""
			(at 0 0 0)
			(layer "B.Fab")
			(effects
				(font
					(size 1.27 1.27)
				)
				(justify mirror)
			)
		)
		(duplicate_pad_numbers_are_jumpers no)
		(fp_line
			(start -0.7874 -0.4064)
			(end -0.7874 0.4064)
			(stroke
				(width 0.1524)
				(type default)
			)
			(layer "B.SilkS")
		)
		(fp_line
			(start -0.7874 0.4064)
			(end 0.7874 0.4064)
			(stroke
				(width 0.1524)
				(type default)
			)
			(layer "B.SilkS")
		)
		(fp_line
			(start 0.7874 -0.4064)
			(end -0.7874 -0.4064)
			(stroke
				(width 0.1524)
				(type default)
			)
			(layer "B.SilkS")
		)
		(fp_line
			(start 0.7874 0.4064)
			(end 0.7874 -0.4064)
			(stroke
				(width 0.1524)
				(type default)
			)
			(layer "B.SilkS")
		)
		(fp_line
			(start -0.67945 -0.3048)
			(end -0.67945 0.3048)
			(stroke
				(width 0.1)
				(type default)
			)
			(layer "B.Fab")
		)
		(fp_line
			(start -0.67945 0.3048)
			(end -0.120396 0.3048)
			(stroke
				(width 0.1)
				(type default)
			)
			(layer "B.Fab")
		)
		(fp_line
			(start -0.12065 -0.3048)
			(end -0.67945 -0.3048)
			(stroke
				(width 0.1)
				(type default)
			)
			(layer "B.Fab")
		)
		(fp_line
			(start -0.12065 -0.2794)
			(end -0.12065 -0.3048)
			(stroke
				(width 0.1)
				(type default)
			)
			(layer "B.Fab")
		)
		(fp_line
			(start -0.120396 0.2794)
			(end 0.12065 0.2794)
			(stroke
				(width 0.1)
				(type default)
			)
			(layer "B.Fab")
		)
		(fp_line
			(start -0.120396 0.3048)
			(end -0.120396 0.2794)
			(stroke
				(width 0.1)
				(type default)
			)
			(layer "B.Fab")
		)
		(fp_line
			(start 0.12065 -0.305054)
			(end 0.12065 -0.2794)
			(stroke
				(width 0.1)
				(type default)
			)
			(layer "B.Fab")
		)
		(fp_line
			(start 0.12065 -0.2794)
			(end -0.12065 -0.2794)
			(stroke
				(width 0.1)
				(type default)
			)
			(layer "B.Fab")
		)
		(fp_line
			(start 0.12065 0.2794)
			(end 0.12065 0.3048)
			(stroke
				(width 0.1)
				(type default)
			)
			(layer "B.Fab")
		)
		(fp_line
			(start 0.12065 0.3048)
			(end 0.67945 0.3048)
			(stroke
				(width 0.1)
				(type default)
			)
			(layer "B.Fab")
		)
		(fp_line
			(start 0.67945 -0.305054)
			(end 0.12065 -0.305054)
			(stroke
				(width 0.1)
				(type default)
			)
			(layer "B.Fab")
		)
		(fp_line
			(start 0.67945 0.3048)
			(end 0.67945 -0.305054)
			(stroke
				(width 0.1)
				(type default)
			)
			(layer "B.Fab")
		)
		(pad "1" smd rect
			(at 0.40005 0)
			(size 0.4572 0.508)
			(layers "B.Cu" "B.Mask" "B.Paste")
			(net "P12V_E1S_0_ISENSE_MPS_TIC")
		)
		(pad "2" smd rect
			(at -0.40005 0)
			(size 0.4572 0.508)
			(layers "B.Cu" "B.Mask" "B.Paste")
			(net "P12V_E1S_0_ISENSE_TIC")
		)
	)
)
